(kicad_pcb
	(version 20260206)
	(generator "pcbnew")
	(generator_version "10.0")
	(general
		(thickness 1.6)
		(legacy_teardrops no)
	)
	(paper "A4")
	(title_block
		(title "01162023_DA0F0TEBIF0_F0T_Expander_BD_F_brd_V02_OCP.brd")
		(comment 1 "Grand Teton / footprints 9328-9336 of 9728")
	)
	(layers
		(0 "F.Cu" signal "TOP")
		(4 "In1.Cu" signal "GND")
		(6 "In2.Cu" signal "VCC")
		(8 "In3.Cu" signal "VCC1")
		(10 "In4.Cu" signal "GND1")
		(12 "In5.Cu" signal "IN1")
		(14 "In6.Cu" signal "GND2")
		(16 "In7.Cu" signal "IN2")
		(18 "In8.Cu" signal "GND3")
		(20 "In9.Cu" signal "IN3")
		(22 "In10.Cu" signal "GND4")
		(24 "In11.Cu" signal "IN4")
		(26 "In12.Cu" signal "GND5")
		(28 "In13.Cu" signal "IN5")
		(30 "In14.Cu" signal "GND6")
		(32 "In15.Cu" signal "IN6")
		(34 "In16.Cu" signal "GND7")
		(2 "B.Cu" signal "BOTTOM")
		(9 "F.Adhes" user "F.Adhesive")
		(11 "B.Adhes" user "B.Adhesive")
		(13 "F.Paste" user "Package Geometry/Pastemask Top")
		(15 "B.Paste" user "Package Geometry/Pastemask Bottom")
		(5 "F.SilkS" user "Ref Des/Silkscreen Top")
		(7 "B.SilkS" user "Ref Des/Silkscreen Bottom")
		(1 "F.Mask" user "Board Geometry/Soldermask Top")
		(3 "B.Mask" user "Board Geometry/Soldermask Bottom")
		(17 "Dwgs.User" user "User.Drawings")
		(19 "Cmts.User" user "User.Comments")
		(21 "Eco1.User" user "User.Eco1")
		(23 "Eco2.User" user "User.Eco2")
		(25 "Edge.Cuts" user "Board Geometry/Outline")
		(27 "Margin" user)
		(31 "F.CrtYd" user "Package Geometry/Place Bound Top")
		(29 "B.CrtYd" user "Package Geometry/Place Bound Bottom")
		(35 "F.Fab" user "Ref Des/Assembly Top")
		(33 "B.Fab" user "Ref Des/Assembly Bottom")
	)
	(footprint ""
		(layer "B.Cu")
		(at 457.216002 -245.02364)
		(property "Reference" "C4432"
			(at 0 0 0)
			(layer "B.SilkS")
			(hide yes)
			(effects
				(font
					(size 1.27 1.27)
				)
				(justify mirror)
			)
		)
		(property "Value" ""
			(at 0 0 0)
			(layer "B.Fab")
			(effects
				(font
					(size 1.27 1.27)
				)
				(justify mirror)
			)
		)
		(duplicate_pad_numbers_are_jumpers no)
		(fp_line
			(start -0.7874 -0.4064)
			(end -0.7874 0.4064)
			(stroke
				(width 0.1524)
				(type default)
			)
			(layer "B.SilkS")
		)
		(fp_line
			(start -0.7874 0.4064)
			(end 0.7874 0.4064)
			(stroke
				(width 0.1524)
				(type default)
			)
			(layer "B.SilkS")
		)
		(fp_line
			(start 0.7874 -0.4064)
			(end -0.7874 -0.4064)
			(stroke
				(width 0.1524)
				(type default)
			)
			(layer "B.SilkS")
		)
		(fp_line
			(start 0.7874 0.4064)
			(end 0.7874 -0.4064)
			(stroke
				(width 0.1524)
				(type default)
			)
			(layer "B.SilkS")
		)
		(fp_line
			(start -0.67945 -0.3048)
			(end -0.67945 0.3048)
			(stroke
				(width 0.1)
				(type default)
			)
			(layer "B.Fab")
		)
		(fp_line
			(start -0.67945 0.3048)
			(end -0.120396 0.3048)
			(stroke
				(width 0.1)
				(type default)
			)
			(layer "B.Fab")
		)
		(fp_line
			(start -0.12065 -0.3048)
			(end -0.67945 -0.3048)
			(stroke
				(width 0.1)
				(type default)
			)
			(layer "B.Fab")
		)
		(fp_line
			(start -0.12065 -0.2794)
			(end -0.12065 -0.3048)
			(stroke
				(width 0.1)
				(type default)
			)
			(layer "B.Fab")
		)
		(fp_line
			(start -0.120396 0.2794)
			(end 0.12065 0.2794)
			(stroke
				(width 0.1)
				(type default)
			)
			(layer "B.Fab")
		)
		(fp_line
			(start -0.120396 0.3048)
			(end -0.120396 0.2794)
			(stroke
				(width 0.1)
				(type default)
			)
			(layer "B.Fab")
		)
		(fp_line
			(start 0.12065 -0.305054)
			(end 0.12065 -0.2794)
			(stroke
				(width 0.1)
				(type default)
			)
			(layer "B.Fab")
		)
		(fp_line
			(start 0.12065 -0.2794)
			(end -0.12065 -0.2794)
			(stroke
				(width 0.1)
				(type default)
			)
			(layer "B.Fab")
		)
		(fp_line
			(start 0.12065 0.2794)
			(end 0.12065 0.3048)
			(stroke
				(width 0.1)
				(type default)
			)
			(layer "B.Fab")
		)
		(fp_line
			(start 0.12065 0.3048)
			(end 0.67945 0.3048)
			(stroke
				(width 0.1)
				(type default)
			)
			(layer "B.Fab")
		)
		(fp_line
			(start 0.67945 -0.305054)
			(end 0.12065 -0.305054)
			(stroke
				(width 0.1)
				(type default)
			)
			(layer "B.Fab")
		)
		(fp_line
			(start 0.67945 0.3048)
			(end 0.67945 -0.305054)
			(stroke
				(width 0.1)
				(type default)
			)
			(layer "B.Fab")
		)
		(pad "1" smd circle
			(at 0.40005 0 180)
			(size 0 0)
			(layers "B.Cu" "B.Mask" "B.Paste")
			(net "P1V8_PLL0_PEX3")
		)
		(pad "2" smd circle
			(at -0.40005 0 180)
			(size 0 0)
			(layers "B.Cu" "B.Mask" "B.Paste")
			(net "GND")
		)
	)
	(footprint ""
		(layer "B.Cu")
		(at 59.649868 -292.099746 90)
		(property "Reference" "C1224"
			(at 0 0 90)
			(layer "B.SilkS")
			(hide yes)
			(effects
				(font
					(size 1.27 1.27)
				)
				(justify mirror)
			)
		)
		(property "Value" ""
			(at 0 0 90)
			(layer "B.Fab")
			(effects
				(font
					(size 1.27 1.27)
				)
				(justify mirror)
			)
		)
		(duplicate_pad_numbers_are_jumpers no)
		(fp_line
			(start 0.299974 -0.150114)
			(end -0.299974 -0.150114)
			(stroke
				(width 0.1)
				(type default)
			)
			(layer "B.Fab")
		)
		(fp_line
			(start -0.299974 -0.150114)
			(end -0.299974 0.150114)
			(stroke
				(width 0.1)
				(type default)
			)
			(layer "B.Fab")
		)
		(fp_line
			(start 0.299974 0.150114)
			(end 0.299974 -0.150114)
			(stroke
				(width 0.1)
				(type default)
			)
			(layer "B.Fab")
		)
		(fp_line
			(start -0.299974 0.150114)
			(end 0.299974 0.150114)
			(stroke
				(width 0.1)
				(type default)
			)
			(layer "B.Fab")
		)
		(pad "1" smd rect
			(at 0.2667 0 270)
			(size 0.3048 0.381)
			(layers "B.Cu" "B.Mask" "B.Paste")
			(net "P0V8_SERDES_VDDA_PEX0")
		)
		(pad "2" smd rect
			(at -0.2667 0 270)
			(size 0.3048 0.381)
			(layers "B.Cu" "B.Mask" "B.Paste")
			(net "GND")
		)
	)
	(footprint ""
		(layer "B.Cu")
		(at 40.173656 -295.79824 180)
		(property "Reference" "R3295"
			(at 0 0 0)
			(layer "B.SilkS")
			(hide yes)
			(effects
				(font
					(size 1.27 1.27)
				)
				(justify mirror)
			)
		)
		(property "Value" ""
			(at 0 0 0)
			(layer "B.Fab")
			(effects
				(font
					(size 1.27 1.27)
				)
				(justify mirror)
			)
		)
		(duplicate_pad_numbers_are_jumpers no)
		(fp_line
			(start 0.7874 0.4064)
			(end 0.7874 -0.4064)
			(stroke
				(width 0.1524)
				(type default)
			)
			(layer "B.SilkS")
		)
		(fp_line
			(start 0.7874 -0.4064)
			(end -0.7874 -0.4064)
			(stroke
				(width 0.1524)
				(type default)
			)
			(layer "B.SilkS")
		)
		(fp_line
			(start -0.7874 0.4064)
			(end 0.7874 0.4064)
			(stroke
				(width 0.1524)
				(type default)
			)
			(layer "B.SilkS")
		)
		(fp_line
			(start -0.7874 -0.4064)
			(end -0.7874 0.4064)
			(stroke
				(width 0.1524)
				(type default)
			)
			(layer "B.SilkS")
		)
		(fp_line
			(start 0.67945 0.3048)
			(end 0.67945 -0.305054)
			(stroke
				(width 0.1)
				(type default)
			)
			(layer "B.Fab")
		)
		(fp_line
			(start 0.67945 -0.305054)
			(end 0.12065 -0.305054)
			(stroke
				(width 0.1)
				(type default)
			)
			(layer "B.Fab")
		)
		(fp_line
			(start 0.12065 0.3048)
			(end 0.67945 0.3048)
			(stroke
				(width 0.1)
				(type default)
			)
			(layer "B.Fab")
		)
		(fp_line
			(start 0.12065 0.2794)
			(end 0.12065 0.3048)
			(stroke
				(width 0.1)
				(type default)
			)
			(layer "B.Fab")
		)
		(fp_line
			(start 0.12065 -0.2794)
			(end -0.12065 -0.2794)
			(stroke
				(width 0.1)
				(type default)
			)
			(layer "B.Fab")
		)
		(fp_line
			(start 0.12065 -0.305054)
			(end 0.12065 -0.2794)
			(stroke
				(width 0.1)
				(type default)
			)
			(layer "B.Fab")
		)
		(fp_line
			(start -0.120396 0.3048)
			(end -0.120396 0.2794)
			(stroke
				(width 0.1)
				(type default)
			)
			(layer "B.Fab")
		)
		(fp_line
			(start -0.120396 0.2794)
			(end 0.12065 0.2794)
			(stroke
				(width 0.1)
				(type default)
			)
			(layer "B.Fab")
		)
		(fp_line
			(start -0.12065 -0.2794)
			(end -0.12065 -0.3048)
			(stroke
				(width 0.1)
				(type default)
			)
			(layer "B.Fab")
		)
		(fp_line
			(start -0.12065 -0.3048)
			(end -0.67945 -0.3048)
			(stroke
				(width 0.1)
				(type default)
			)
			(layer "B.Fab")
		)
		(fp_line
			(start -0.67945 0.3048)
			(end -0.120396 0.3048)
			(stroke
				(width 0.1)
				(type default)
			)
			(layer "B.Fab")
		)
		(fp_line
			(start -0.67945 -0.3048)
			(end -0.67945 0.3048)
			(stroke
				(width 0.1)
				(type default)
			)
			(layer "B.Fab")
		)
		(pad "1" smd circle
			(at 0.40005 0)
			(size 0 0)
			(layers "B.Cu" "B.Mask" "B.Paste")
			(net "SPI_PEX0_SDIO0_R")
		)
		(pad "2" smd circle
			(at -0.40005 0)
			(size 0 0)
			(layers "B.Cu" "B.Mask" "B.Paste")
			(net "SPI_PEX0_SDIO0")
		)
	)
	(footprint ""
		(layer "B.Cu")
		(at 49.67478 -297.79976 90)
		(property "Reference" "C1152"
			(at 0 0 90)
			(layer "B.SilkS")
			(hide yes)
			(effects
				(font
					(size 1.27 1.27)
				)
				(justify mirror)
			)
		)
		(property "Value" ""
			(at 0 0 90)
			(layer "B.Fab")
			(effects
				(font
					(size 1.27 1.27)
				)
				(justify mirror)
			)
		)
		(duplicate_pad_numbers_are_jumpers no)
		(fp_line
			(start 0.299974 -0.150114)
			(end -0.299974 -0.150114)
			(stroke
				(width 0.1)
				(type default)
			)
			(layer "B.Fab")
		)
		(fp_line
			(start -0.299974 -0.150114)
			(end -0.299974 0.150114)
			(stroke
				(width 0.1)
				(type default)
			)
			(layer "B.Fab")
		)
		(fp_line
			(start 0.299974 0.150114)
			(end 0.299974 -0.150114)
			(stroke
				(width 0.1)
				(type default)
			)
			(layer "B.Fab")
		)
		(fp_line
			(start -0.299974 0.150114)
			(end 0.299974 0.150114)
			(stroke
				(width 0.1)
				(type default)
			)
			(layer "B.Fab")
		)
		(pad "1" smd rect
			(at 0.2667 0 270)
			(size 0.3048 0.381)
			(layers "B.Cu" "B.Mask" "B.Paste")
			(net "P0V8_PEX0")
		)
		(pad "2" smd rect
			(at -0.2667 0 270)
			(size 0.3048 0.381)
			(layers "B.Cu" "B.Mask" "B.Paste")
			(net "GND")
		)
	)
	(footprint ""
		(layer "B.Cu")
		(at 67.249802 -296.37482)
		(property "Reference" "C1192"
			(at 0 0 0)
			(layer "B.SilkS")
			(hide yes)
			(effects
				(font
					(size 1.27 1.27)
				)
				(justify mirror)
			)
		)
		(property "Value" ""
			(at 0 0 0)
			(layer "B.Fab")
			(effects
				(font
					(size 1.27 1.27)
				)
				(justify mirror)
			)
		)
		(duplicate_pad_numbers_are_jumpers no)
		(fp_line
			(start -0.299974 -0.150114)
			(end -0.299974 0.150114)
			(stroke
				(width 0.1)
				(type default)
			)
			(layer "B.Fab")
		)
		(fp_line
			(start -0.299974 0.150114)
			(end 0.299974 0.150114)
			(stroke
				(width 0.1)
				(type default)
			)
			(layer "B.Fab")
		)
		(fp_line
			(start 0.299974 -0.150114)
			(end -0.299974 -0.150114)
			(stroke
				(width 0.1)
				(type default)
			)
			(layer "B.Fab")
		)
		(fp_line
			(start 0.299974 0.150114)
			(end 0.299974 -0.150114)
			(stroke
				(width 0.1)
				(type default)
			)
			(layer "B.Fab")
		)
		(pad "1" smd rect
			(at 0.2667 0 180)
			(size 0.3048 0.381)
			(layers "B.Cu" "B.Mask" "B.Paste")
			(net "P0V8_SERDES_VDDA_PEX0")
		)
		(pad "2" smd rect
			(at -0.2667 0 180)
			(size 0.3048 0.381)
			(layers "B.Cu" "B.Mask" "B.Paste")
			(net "GND")
		)
	)
	(footprint ""
		(layer "B.Cu")
		(at 394.65504 -292.57498)
		(property "Reference" "C3578"
			(at 0 0 0)
			(layer "B.SilkS")
			(hide yes)
			(effects
				(font
					(size 1.27 1.27)
				)
				(justify mirror)
			)
		)
		(property "Value" ""
			(at 0 0 0)
			(layer "B.Fab")
			(effects
				(font
					(size 1.27 1.27)
				)
				(justify mirror)
			)
		)
		(duplicate_pad_numbers_are_jumpers no)
		(fp_line
			(start -0.299974 -0.150114)
			(end -0.299974 0.150114)
			(stroke
				(width 0.1)
				(type default)
			)
			(layer "B.Fab")
		)
		(fp_line
			(start -0.299974 0.150114)
			(end 0.299974 0.150114)
			(stroke
				(width 0.1)
				(type default)
			)
			(layer "B.Fab")
		)
		(fp_line
			(start 0.299974 -0.150114)
			(end -0.299974 -0.150114)
			(stroke
				(width 0.1)
				(type default)
			)
			(layer "B.Fab")
		)
		(fp_line
			(start 0.299974 0.150114)
			(end 0.299974 -0.150114)
			(stroke
				(width 0.1)
				(type default)
			)
			(layer "B.Fab")
		)
		(pad "1" smd rect
			(at 0.2667 0 180)
			(size 0.3048 0.381)
			(layers "B.Cu" "B.Mask" "B.Paste")
			(net "PCEPLL6_VDDA18_PEX3")
		)
		(pad "2" smd rect
			(at -0.2667 0 180)
			(size 0.3048 0.381)
			(layers "B.Cu" "B.Mask" "B.Paste")
			(net "GND")
		)
	)
	(footprint ""
		(layer "B.Cu")
		(at 363.252766 -308.613556 90)
		(property "Reference" "C4373"
			(at 0 0 90)
			(layer "B.SilkS")
			(hide yes)
			(effects
				(font
					(size 1.27 1.27)
				)
				(justify mirror)
			)
		)
		(property "Value" ""
			(at 0 0 90)
			(layer "B.Fab")
			(effects
				(font
					(size 1.27 1.27)
				)
				(justify mirror)
			)
		)
		(duplicate_pad_numbers_are_jumpers no)
		(fp_line
			(start 1.2954 -0.5842)
			(end -1.2954 -0.5842)
			(stroke
				(width 0.1524)
				(type default)
			)
			(layer "B.SilkS")
		)
		(fp_line
			(start -1.2954 -0.5842)
			(end -1.2954 0.5842)
			(stroke
				(width 0.1524)
				(type default)
			)
			(layer "B.SilkS")
		)
		(fp_line
			(start 1.2954 0.5842)
			(end 1.2954 -0.5842)
			(stroke
				(width 0.1524)
				(type default)
			)
			(layer "B.SilkS")
		)
		(fp_line
			(start -1.2954 0.5842)
			(end 1.2954 0.5842)
			(stroke
				(width 0.1524)
				(type default)
			)
			(layer "B.SilkS")
		)
		(fp_line
			(start 0.8636 -0.4572)
			(end -0.8636 -0.4572)
			(stroke
				(width 0.1)
				(type default)
			)
			(layer "B.Fab")
		)
		(fp_line
			(start -0.8636 -0.4572)
			(end -0.8636 -0.4064)
			(stroke
				(width 0.1)
				(type default)
			)
			(layer "B.Fab")
		)
		(fp_line
			(start 1.1938 -0.4064)
			(end 0.8636 -0.4064)
			(stroke
				(width 0.1)
				(type default)
			)
			(layer "B.Fab")
		)
		(fp_line
			(start 0.8636 -0.4064)
			(end 0.8636 -0.4572)
			(stroke
				(width 0.1)
				(type default)
			)
			(layer "B.Fab")
		)
		(fp_line
			(start -0.8636 -0.4064)
			(end -1.1938 -0.4064)
			(stroke
				(width 0.1)
				(type default)
			)
			(layer "B.Fab")
		)
		(fp_line
			(start -1.1938 -0.4064)
			(end -1.1938 0.4064)
			(stroke
				(width 0.1)
				(type default)
			)
			(layer "B.Fab")
		)
		(fp_line
			(start 1.1938 0.4064)
			(end 1.1938 -0.4064)
			(stroke
				(width 0.1)
				(type default)
			)
			(layer "B.Fab")
		)
		(fp_line
			(start 0.8636 0.4064)
			(end 1.1938 0.4064)
			(stroke
				(width 0.1)
				(type default)
			)
			(layer "B.Fab")
		)
		(fp_line
			(start -0.8636 0.4064)
			(end -0.8636 0.4572)
			(stroke
				(width 0.1)
				(type default)
			)
			(layer "B.Fab")
		)
		(fp_line
			(start -1.1938 0.4064)
			(end -0.8636 0.4064)
			(stroke
				(width 0.1)
				(type default)
			)
			(layer "B.Fab")
		)
		(fp_line
			(start 0.8636 0.4572)
			(end 0.8636 0.4064)
			(stroke
				(width 0.1)
				(type default)
			)
			(layer "B.Fab")
		)
		(fp_line
			(start -0.8636 0.4572)
			(end 0.8636 0.4572)
			(stroke
				(width 0.1)
				(type default)
			)
			(layer "B.Fab")
		)
		(pad "1" smd rect
			(at 0.7366 0)
			(size 0.7112 0.8128)
			(layers "B.Cu" "B.Mask" "B.Paste")
			(net "P0V8_PEX3")
		)
		(pad "2" smd rect
			(at -0.7366 0)
			(size 0.7112 0.8128)
			(layers "B.Cu" "B.Mask" "B.Paste")
			(net "GND")
		)
	)
	(footprint ""
		(layer "B.Cu")
		(at 396.0749 -295.3766 90)
		(property "Reference" "C3562"
			(at 0 0 90)
			(layer "B.SilkS")
			(hide yes)
			(effects
				(font
					(size 1.27 1.27)
				)
				(justify mirror)
			)
		)
		(property "Value" ""
			(at 0 0 90)
			(layer "B.Fab")
			(effects
				(font
					(size 1.27 1.27)
				)
				(justify mirror)
			)
		)
		(duplicate_pad_numbers_are_jumpers no)
		(fp_line
			(start 0.299974 -0.150114)
			(end -0.299974 -0.150114)
			(stroke
				(width 0.1)
				(type default)
			)
			(layer "B.Fab")
		)
		(fp_line
			(start -0.299974 -0.150114)
			(end -0.299974 0.150114)
			(stroke
				(width 0.1)
				(type default)
			)
			(layer "B.Fab")
		)
		(fp_line
			(start 0.299974 0.150114)
			(end 0.299974 -0.150114)
			(stroke
				(width 0.1)
				(type default)
			)
			(layer "B.Fab")
		)
		(fp_line
			(start -0.299974 0.150114)
			(end 0.299974 0.150114)
			(stroke
				(width 0.1)
				(type default)
			)
			(layer "B.Fab")
		)
		(pad "1" smd rect
			(at 0.2667 0 270)
			(size 0.3048 0.381)
			(layers "B.Cu" "B.Mask" "B.Paste")
			(net "PCEPLL3_VDDA18_PEX3")
		)
		(pad "2" smd rect
			(at -0.2667 0 270)
			(size 0.3048 0.381)
			(layers "B.Cu" "B.Mask" "B.Paste")
			(net "GND")
		)
	)
	(footprint ""
		(layer "B.Cu")
		(at 403.199854 -299.699934 -90)
		(property "Reference" "C1985"
			(at 0 0 90)
			(layer "B.SilkS")
			(hide yes)
			(effects
				(font
					(size 1.27 1.27)
				)
				(justify mirror)
			)
		)
		(property "Value" ""
			(at 0 0 90)
			(layer "B.Fab")
			(effects
				(font
					(size 1.27 1.27)
				)
				(justify mirror)
			)
		)
		(duplicate_pad_numbers_are_jumpers no)
		(fp_line
			(start -0.299974 0.150114)
			(end 0.299974 0.150114)
			(stroke
				(width 0.1)
				(type default)
			)
			(layer "B.Fab")
		)
		(fp_line
			(start 0.299974 0.150114)
			(end 0.299974 -0.150114)
			(stroke
				(width 0.1)
				(type default)
			)
			(layer "B.Fab")
		)
		(fp_line
			(start -0.299974 -0.150114)
			(end -0.299974 0.150114)
			(stroke
				(width 0.1)
				(type default)
			)
			(layer "B.Fab")
		)
		(fp_line
			(start 0.299974 -0.150114)
			(end -0.299974 -0.150114)
			(stroke
				(width 0.1)
				(type default)
			)
			(layer "B.Fab")
		)
		(pad "1" smd rect
			(at 0.2667 0 90)
			(size 0.3048 0.381)
			(layers "B.Cu" "B.Mask" "B.Paste")
			(net "P0V8_SERDES_VDDA_PEX3")
		)
		(pad "2" smd rect
			(at -0.2667 0 90)
			(size 0.3048 0.381)
			(layers "B.Cu" "B.Mask" "B.Paste")
			(net "GND")
		)
	)
)
